(kicad_pcb
	(version 20241229)
	(generator "pcbnew")
	(generator_version "9.0")
	(general
		(thickness 1.6642)
		(legacy_teardrops no)
	)
	(paper "A3")
	(title_block
		(title "PolarFire SoM")
		(date "2025-07-22")
		(rev "1.1.4")
		(company "Antmicro Ltd")
		(comment 1 "www.antmicro.com")
		(comment 9 "footprints 86-90 of 470")
	)
	(layers
		(0 "F.Cu" mixed)
		(4 "In1.Cu" power)
		(6 "In2.Cu" signal)
		(8 "In3.Cu" power)
		(10 "In4.Cu" signal)
		(12 "In5.Cu" power)
		(14 "In6.Cu" power)
		(16 "In7.Cu" signal)
		(18 "In8.Cu" power)
		(20 "In9.Cu" signal)
		(22 "In10.Cu" power)
		(24 "In11.Cu" signal)
		(26 "In12.Cu" signal)
		(2 "B.Cu" mixed)
		(9 "F.Adhes" user "F.Adhesive")
		(11 "B.Adhes" user "B.Adhesive")
		(13 "F.Paste" user)
		(15 "B.Paste" user)
		(5 "F.SilkS" user "F.Silkscreen")
		(7 "B.SilkS" user "B.Silkscreen")
		(1 "F.Mask" user)
		(3 "B.Mask" user)
		(17 "Dwgs.User" user "User.Drawings")
		(19 "Cmts.User" user "User.Comments")
		(21 "Eco1.User" user "User.Eco1")
		(23 "Eco2.User" user "User.Eco2")
		(25 "Edge.Cuts" user)
		(27 "Margin" user)
		(31 "F.CrtYd" user "F.Courtyard")
		(29 "B.CrtYd" user "B.Courtyard")
		(35 "F.Fab" user)
		(33 "B.Fab" user)
	)
	(footprint "antmicro-footprints:FB_0402_1005Metric"
		(layer "F.Cu")
		(at 208.085 149.74)
		(descr "Ferrite Bead SMD 0402")
		(tags "ferrite bead SMD 0402")
		(property "Reference" "FB11"
			(at -2.195 4.575 90)
			(layer "F.SilkS")
			(effects
				(font
					(size 0.7 0.7)
					(thickness 0.15)
				)
				(justify left bottom)
			)
		)
		(property "Value" "FB_120Z_1.2A_TDK-MPZ_0402"
			(at 0 1.4 0)
			(layer "F.Fab")
			(hide yes)
			(effects
				(font
					(size 0.7 0.7)
					(thickness 0.15)
				)
				(justify left bottom)
			)
		)
		(property "Datasheet" "https://product.tdk.com/en/search/emc/emc/beads/info?part_no=MPZ1005S121CT000"
			(at 0 0 0)
			(layer "F.Fab")
			(hide yes)
			(effects
				(font
					(size 1.27 1.27)
					(thickness 0.15)
				)
			)
		)
		(property "Description" "Ferrite Bead, 0402 [1005 Metric], 120 ohm, 1.2A, MPZ, 0.06 ohm, ± 25%, DC Power line"
			(at 0 0 0)
			(layer "F.Fab")
			(hide yes)
			(effects
				(font
					(size 1.27 1.27)
					(thickness 0.15)
				)
			)
		)
		(property "Author" "Antmicro"
			(at 0 0 0)
			(layer "F.Fab")
			(hide yes)
			(effects
				(font
					(size 1 1)
					(thickness 0.15)
				)
			)
		)
		(property "Current" ""
			(at 0 0 0)
			(layer "F.Fab")
			(hide yes)
			(effects
				(font
					(size 1 1)
					(thickness 0.15)
				)
			)
		)
		(property "License" "Apache-2.0"
			(at 0 0 0)
			(layer "F.Fab")
			(hide yes)
			(effects
				(font
					(size 1 1)
					(thickness 0.15)
				)
			)
		)
		(property "MPN" "MPZ1005S121CT000"
			(at 0 0 0)
			(layer "F.Fab")
			(hide yes)
			(effects
				(font
					(size 1 1)
					(thickness 0.15)
				)
			)
		)
		(property "Manufacturer" "TDK"
			(at 0 0 0)
			(layer "F.Fab")
			(hide yes)
			(effects
				(font
					(size 1 1)
					(thickness 0.15)
				)
			)
		)
		(property "Public" ""
			(at 0 0 0)
			(layer "F.Fab")
			(hide yes)
			(effects
				(font
					(size 1 1)
					(thickness 0.15)
				)
			)
		)
		(property "Val" "120Z/1.2A"
			(at 0 0 0)
			(layer "F.Fab")
			(hide yes)
			(effects
				(font
					(size 1 1)
					(thickness 0.15)
				)
			)
		)
		(sheetname "/MIPI CrossLink/")
		(sheetfile "crosslink.kicad_sch")
		(attr smd)
		(fp_rect
			(start -0.925 -0.47)
			(end 0.925 0.47)
			(stroke
				(width 0.05)
				(type default)
			)
			(fill no)
			(layer "F.CrtYd")
		)
		(fp_rect
			(start -0.5 -0.25)
			(end 0.5 0.25)
			(stroke
				(width 0.15)
				(type solid)
			)
			(fill no)
			(layer "F.Fab")
		)
		(fp_text user "Author: Antmicro"
			(at -0.95 4.169 0)
			(layer "F.Fab")
			(effects
				(font
					(size 0.7 0.7)
					(thickness 0.15)
				)
				(justify left bottom)
			)
		)
		(fp_text user "License: Apache-2.0"
			(at -0.95 5.169 0)
			(layer "F.Fab")
			(effects
				(font
					(size 0.7 0.7)
					(thickness 0.15)
				)
				(justify left bottom)
			)
		)
		(fp_text user "${REFERENCE}"
			(at -0.95 3.168 0)
			(layer "F.Fab")
			(effects
				(font
					(size 0.7 0.7)
					(thickness 0.15)
				)
				(justify left bottom)
			)
		)
		(pad "1" smd roundrect
			(at -0.48 0)
			(size 0.59 0.64)
			(layers "F.Cu" "F.Mask" "F.Paste")
			(roundrect_rratio 0.25)
			(net 211 "/MIPI CrossLink/CL_VCCPLL_DPHY1")
			(pintype "passive")
		)
		(pad "2" smd roundrect
			(at 0.48 0)
			(size 0.59 0.64)
			(layers "F.Cu" "F.Mask" "F.Paste")
			(roundrect_rratio 0.25)
			(net 96 "+1V2")
			(pintype "passive")
		)
	)
	(footprint "antmicro-footprints:C_0402_1005Metric"
		(layer "F.Cu")
		(at 185 140.9675 90)
		(descr "Capacitor SMD 0402")
		(tags "capacitor SMD 0402")
		(property "Reference" "C100"
			(at 0.8375 0.43 90)
			(layer "F.SilkS")
			(effects
				(font
					(size 0.7 0.7)
					(thickness 0.15)
				)
				(justify left bottom)
			)
		)
		(property "Value" "C_22u_0402"
			(at -1.022927 2.155213 90)
			(layer "F.Fab")
			(hide yes)
			(effects
				(font
					(size 0.7 0.7)
					(thickness 0.15)
				)
				(justify left bottom)
			)
		)
		(property "Datasheet" "https://www.murata.com/products/productdetail?partno=GRM158R60J226ME01%23"
			(at 0 0 90)
			(layer "F.Fab")
			(hide yes)
			(effects
				(font
					(size 1.27 1.27)
					(thickness 0.15)
				)
			)
		)
		(property "Description" "SMD Multilayer Ceramic Capacitor, 22 uF, 4 V, 0402 [1005 Metric], X6S"
			(at 0 0 90)
			(layer "F.Fab")
			(hide yes)
			(effects
				(font
					(size 1.27 1.27)
					(thickness 0.15)
				)
			)
		)
		(property "Author" "Antmicro"
			(at 325.9675 -44.0325 0)
			(layer "F.Fab")
			(hide yes)
			(effects
				(font
					(size 1 1)
					(thickness 0.15)
				)
			)
		)
		(property "Dielectric" ""
			(at 325.9675 -44.0325 0)
			(layer "F.Fab")
			(hide yes)
			(effects
				(font
					(size 1 1)
					(thickness 0.15)
				)
			)
		)
		(property "License" "Apache-2.0"
			(at 325.9675 -44.0325 0)
			(layer "F.Fab")
			(hide yes)
			(effects
				(font
					(size 1 1)
					(thickness 0.15)
				)
			)
		)
		(property "MPN" "GRM158R60J226ME01D"
			(at 325.9675 -44.0325 0)
			(layer "F.Fab")
			(hide yes)
			(effects
				(font
					(size 1 1)
					(thickness 0.15)
				)
			)
		)
		(property "Manufacturer" "Murata"
			(at 325.9675 -44.0325 0)
			(layer "F.Fab")
			(hide yes)
			(effects
				(font
					(size 1 1)
					(thickness 0.15)
				)
			)
		)
		(property "Public" ""
			(at 325.9675 -44.0325 0)
			(layer "F.Fab")
			(hide yes)
			(effects
				(font
					(size 1 1)
					(thickness 0.15)
				)
			)
		)
		(property "Val" "22u"
			(at 325.9675 -44.0325 0)
			(layer "F.Fab")
			(hide yes)
			(effects
				(font
					(size 1 1)
					(thickness 0.15)
				)
			)
		)
		(property "Voltage" ""
			(at 325.9675 -44.0325 0)
			(layer "F.Fab")
			(hide yes)
			(effects
				(font
					(size 1 1)
					(thickness 0.15)
				)
			)
		)
		(sheetname "/Supply/")
		(sheetfile "supply.kicad_sch")
		(attr smd)
		(fp_rect
			(start -0.925 -0.47)
			(end 0.925 0.47)
			(stroke
				(width 0.05)
				(type default)
			)
			(fill no)
			(layer "F.CrtYd")
		)
		(fp_line
			(start 0.504 -0.25)
			(end 0.504 0.248)
			(stroke
				(width 0.15)
				(type solid)
			)
			(layer "F.Fab")
		)
		(fp_line
			(start -0.494 -0.25)
			(end 0.504 -0.25)
			(stroke
				(width 0.15)
				(type solid)
			)
			(layer "F.Fab")
		)
		(fp_line
			(start 0.504 0.248)
			(end -0.494 0.248)
			(stroke
				(width 0.15)
				(type solid)
			)
			(layer "F.Fab")
		)
		(fp_line
			(start -0.494 0.248)
			(end -0.494 -0.25)
			(stroke
				(width 0.15)
				(type solid)
			)
			(layer "F.Fab")
		)
		(fp_text user "License: Apache-2.0"
			(at -0.939 5.799 90)
			(layer "F.Fab")
			(effects
				(font
					(size 0.7 0.7)
					(thickness 0.15)
				)
				(justify left bottom)
			)
		)
		(fp_text user "Author: Antmicro"
			(at -0.939 3.399 90)
			(layer "F.Fab")
			(effects
				(font
					(size 0.7 0.7)
					(thickness 0.15)
				)
				(justify left bottom)
			)
		)
		(fp_text user "${REFERENCE}"
			(at -0.939 4.599 90)
			(layer "F.Fab")
			(effects
				(font
					(size 0.7 0.7)
					(thickness 0.15)
				)
				(justify left bottom)
			)
		)
		(pad "1" smd roundrect
			(at -0.48 0 90)
			(size 0.59 0.64)
			(layers "F.Cu" "F.Mask" "F.Paste")
			(roundrect_rratio 0.25)
			(net 417 "GND")
			(pintype "passive")
		)
		(pad "2" smd roundrect
			(at 0.48 0 90)
			(size 0.59 0.64)
			(layers "F.Cu" "F.Mask" "F.Paste")
			(roundrect_rratio 0.25)
			(net 272 "/Supply/SENSE3_P")
			(pintype "passive")
		)
	)
	(footprint "antmicro-footprints:R_0402_1005Metric"
		(layer "F.Cu")
		(at 213.225 139.2 180)
		(descr "Resistor SMD 0402")
		(tags "resistor SMD 0402")
		(property "Reference" "R59"
			(at -1.925 -0.42 180)
			(layer "F.SilkS")
			(effects
				(font
					(size 0.7 0.7)
					(thickness 0.15)
				)
				(justify left bottom)
			)
		)
		(property "Value" "R_1k_0402"
			(at -1.011843 1.772047 180)
			(layer "F.Fab")
			(hide yes)
			(effects
				(font
					(size 0.7 0.7)
					(thickness 0.15)
				)
				(justify left bottom)
			)
		)
		(property "Datasheet" "https://www.bourns.com/docs/product-datasheets/cr.pdf"
			(at 0 0 180)
			(layer "F.Fab")
			(hide yes)
			(effects
				(font
					(size 1.27 1.27)
					(thickness 0.15)
				)
			)
		)
		(property "Description" "SMD Chip Resistor, 1 kohm, ± 1%, 63 mW, 0402 [1005 Metric], Thick Film, General Purpose"
			(at 0 0 180)
			(layer "F.Fab")
			(hide yes)
			(effects
				(font
					(size 1.27 1.27)
					(thickness 0.15)
				)
			)
		)
		(property "Author" "Antmicro"
			(at 426.45 278.4 0)
			(layer "F.Fab")
			(hide yes)
			(effects
				(font
					(size 1 1)
					(thickness 0.15)
				)
			)
		)
		(property "License" "Apache-2.0"
			(at 426.45 278.4 0)
			(layer "F.Fab")
			(hide yes)
			(effects
				(font
					(size 1 1)
					(thickness 0.15)
				)
			)
		)
		(property "MPN" "CR0402-FX-1001GLF"
			(at 426.45 278.4 0)
			(layer "F.Fab")
			(hide yes)
			(effects
				(font
					(size 1 1)
					(thickness 0.15)
				)
			)
		)
		(property "Manufacturer" "Bourns"
			(at 426.45 278.4 0)
			(layer "F.Fab")
			(hide yes)
			(effects
				(font
					(size 1 1)
					(thickness 0.15)
				)
			)
		)
		(property "Public" ""
			(at 426.45 278.4 0)
			(layer "F.Fab")
			(hide yes)
			(effects
				(font
					(size 1 1)
					(thickness 0.15)
				)
			)
		)
		(property "Tolerance" "1%"
			(at 426.45 278.4 0)
			(layer "F.Fab")
			(hide yes)
			(effects
				(font
					(size 1 1)
					(thickness 0.15)
				)
			)
		)
		(property "Val" "1k"
			(at 426.45 278.4 0)
			(layer "F.Fab")
			(hide yes)
			(effects
				(font
					(size 1 1)
					(thickness 0.15)
				)
			)
		)
		(sheetname "/USB/")
		(sheetfile "usb.kicad_sch")
		(attr smd)
		(fp_rect
			(start -0.925 -0.47)
			(end 0.925 0.47)
			(stroke
				(width 0.05)
				(type default)
			)
			(fill no)
			(layer "F.CrtYd")
		)
		(fp_rect
			(start -0.5 -0.25)
			(end 0.5 0.25)
			(stroke
				(width 0.15)
				(type solid)
			)
			(fill no)
			(layer "F.Fab")
		)
		(fp_text user "${REFERENCE}"
			(at -0.95 3.168 180)
			(layer "F.Fab")
			(effects
				(font
					(size 0.7 0.7)
					(thickness 0.15)
				)
				(justify left bottom)
			)
		)
		(fp_text user "License: Apache-2.0"
			(at -0.95 5.169 180)
			(layer "F.Fab")
			(effects
				(font
					(size 0.7 0.7)
					(thickness 0.15)
				)
				(justify left bottom)
			)
		)
		(fp_text user "Author: Antmicro"
			(at -0.95 4.169 180)
			(layer "F.Fab")
			(effects
				(font
					(size 0.7 0.7)
					(thickness 0.15)
				)
				(justify left bottom)
			)
		)
		(pad "1" smd roundrect
			(at -0.48 0 180)
			(size 0.59 0.64)
			(layers "F.Cu" "F.Mask" "F.Paste")
			(roundrect_rratio 0.25)
			(net 221 "VBUS")
			(pintype "passive")
		)
		(pad "2" smd roundrect
			(at 0.48 0 180)
			(size 0.59 0.64)
			(layers "F.Cu" "F.Mask" "F.Paste")
			(roundrect_rratio 0.25)
			(net 90 "+5V")
			(pintype "passive")
		)
	)
	(footprint "antmicro-footprints:FB_0402_1005Metric"
		(layer "F.Cu")
		(at 208.06 152.67)
		(descr "Ferrite Bead SMD 0402")
		(tags "ferrite bead SMD 0402")
		(property "Reference" "FB7"
			(at -1.02 2.45 180)
			(layer "F.SilkS")
			(effects
				(font
					(size 0.7 0.7)
					(thickness 0.15)
				)
				(justify left bottom)
			)
		)
		(property "Value" "FB_120Z_1.2A_TDK-MPZ_0402"
			(at 0 1.4 0)
			(layer "F.Fab")
			(hide yes)
			(effects
				(font
					(size 0.7 0.7)
					(thickness 0.15)
				)
				(justify left bottom)
			)
		)
		(property "Datasheet" "https://product.tdk.com/en/search/emc/emc/beads/info?part_no=MPZ1005S121CT000"
			(at 0 0 0)
			(layer "F.Fab")
			(hide yes)
			(effects
				(font
					(size 1.27 1.27)
					(thickness 0.15)
				)
			)
		)
		(property "Description" "Ferrite Bead, 0402 [1005 Metric], 120 ohm, 1.2A, MPZ, 0.06 ohm, ± 25%, DC Power line"
			(at 0 0 0)
			(layer "F.Fab")
			(hide yes)
			(effects
				(font
					(size 1.27 1.27)
					(thickness 0.15)
				)
			)
		)
		(property "Author" "Antmicro"
			(at 0 0 0)
			(layer "F.Fab")
			(hide yes)
			(effects
				(font
					(size 1 1)
					(thickness 0.15)
				)
			)
		)
		(property "Current" ""
			(at 0 0 0)
			(layer "F.Fab")
			(hide yes)
			(effects
				(font
					(size 1 1)
					(thickness 0.15)
				)
			)
		)
		(property "License" "Apache-2.0"
			(at 0 0 0)
			(layer "F.Fab")
			(hide yes)
			(effects
				(font
					(size 1 1)
					(thickness 0.15)
				)
			)
		)
		(property "MPN" "MPZ1005S121CT000"
			(at 0 0 0)
			(layer "F.Fab")
			(hide yes)
			(effects
				(font
					(size 1 1)
					(thickness 0.15)
				)
			)
		)
		(property "Manufacturer" "TDK"
			(at 0 0 0)
			(layer "F.Fab")
			(hide yes)
			(effects
				(font
					(size 1 1)
					(thickness 0.15)
				)
			)
		)
		(property "Public" ""
			(at 0 0 0)
			(layer "F.Fab")
			(hide yes)
			(effects
				(font
					(size 1 1)
					(thickness 0.15)
				)
			)
		)
		(property "Val" "120Z/1.2A"
			(at 0 0 0)
			(layer "F.Fab")
			(hide yes)
			(effects
				(font
					(size 1 1)
					(thickness 0.15)
				)
			)
		)
		(sheetname "/MIPI CrossLink/")
		(sheetfile "crosslink.kicad_sch")
		(attr smd)
		(fp_rect
			(start -0.925 -0.47)
			(end 0.925 0.47)
			(stroke
				(width 0.05)
				(type default)
			)
			(fill no)
			(layer "F.CrtYd")
		)
		(fp_rect
			(start -0.5 -0.25)
			(end 0.5 0.25)
			(stroke
				(width 0.15)
				(type solid)
			)
			(fill no)
			(layer "F.Fab")
		)
		(fp_text user "License: Apache-2.0"
			(at -0.95 5.169 0)
			(layer "F.Fab")
			(effects
				(font
					(size 0.7 0.7)
					(thickness 0.15)
				)
				(justify left bottom)
			)
		)
		(fp_text user "${REFERENCE}"
			(at -0.95 3.168 0)
			(layer "F.Fab")
			(effects
				(font
					(size 0.7 0.7)
					(thickness 0.15)
				)
				(justify left bottom)
			)
		)
		(fp_text user "Author: Antmicro"
			(at -0.95 4.169 0)
			(layer "F.Fab")
			(effects
				(font
					(size 0.7 0.7)
					(thickness 0.15)
				)
				(justify left bottom)
			)
		)
		(pad "1" smd roundrect
			(at -0.48 0)
			(size 0.59 0.64)
			(layers "F.Cu" "F.Mask" "F.Paste")
			(roundrect_rratio 0.25)
			(net 203 "/MIPI CrossLink/CL_VCCA_DPHY0")
			(pintype "passive")
		)
		(pad "2" smd roundrect
			(at 0.48 0)
			(size 0.59 0.64)
			(layers "F.Cu" "F.Mask" "F.Paste")
			(roundrect_rratio 0.25)
			(net 96 "+1V2")
			(pintype "passive")
		)
	)
	(footprint "antmicro-footprints:XSON-8_1x1.95mm_P0.5mm"
		(layer "F.Cu")
		(at 193.5 120.9)
		(property "Reference" "U20"
			(at -0.36 -1.21 0)
			(layer "F.SilkS")
			(effects
				(font
					(size 0.7 0.7)
					(thickness 0.15)
				)
				(justify left bottom)
			)
		)
		(property "Value" "NTS0102_XSON"
			(at 0 2.2 0)
			(layer "F.Fab")
			(hide yes)
			(effects
				(font
					(size 0.7 0.7)
					(thickness 0.15)
				)
				(justify left bottom)
			)
		)
		(property "Datasheet" "http://www.farnell.com/datasheets/1760723.pdf"
			(at 0 0 0)
			(layer "F.Fab")
			(hide yes)
			(effects
				(font
					(size 1.27 1.27)
					(thickness 0.15)
				)
			)
		)
		(property "Description" "Transceiver, 1.65 V to 3.6 V, XSON-8"
			(at 0 0 0)
			(layer "F.Fab")
			(hide yes)
			(effects
				(font
					(size 1.27 1.27)
					(thickness 0.15)
				)
			)
		)
		(property "Author" "Antmicro"
			(at 0 0 0)
			(layer "F.Fab")
			(hide yes)
			(effects
				(font
					(size 1 1)
					(thickness 0.15)
				)
			)
		)
		(property "License" "Apache-2.0"
			(at 0 0 0)
			(layer "F.Fab")
			(hide yes)
			(effects
				(font
					(size 1 1)
					(thickness 0.15)
				)
			)
		)
		(property "MPN" "NTS0102GT"
			(at 0 0 0)
			(layer "F.Fab")
			(hide yes)
			(effects
				(font
					(size 1 1)
					(thickness 0.15)
				)
			)
		)
		(property "Manufacturer" "NXP"
			(at 0 0 0)
			(layer "F.Fab")
			(hide yes)
			(effects
				(font
					(size 1 1)
					(thickness 0.15)
				)
			)
		)
		(sheetname "/FPGA GPIO/")
		(sheetfile "fpga-gpio.kicad_sch")
		(attr smd)
		(fp_line
			(start -0.5 -1.1)
			(end 0.5 -1.1)
			(stroke
				(width 0.15)
				(type solid)
			)
			(layer "F.SilkS")
		)
		(fp_line
			(start 0.5 1.1)
			(end -0.5 1.1)
			(stroke
				(width 0.15)
				(type solid)
			)
			(layer "F.SilkS")
		)
		(fp_circle
			(center -0.75 -1.1)
			(end -0.701 -1.1)
			(stroke
				(width 0.15)
				(type solid)
			)
			(fill no)
			(layer "F.SilkS")
		)
		(fp_rect
			(start -0.8 -1.2)
			(end 0.8 1.2)
			(stroke
				(width 0.05)
				(type solid)
			)
			(fill no)
			(layer "F.CrtYd")
		)
		(fp_line
			(start -0.5305 -1.001)
			(end 0.5305 -1.001)
			(stroke
				(width 0.15)
				(type solid)
			)
			(layer "F.Fab")
		)
		(fp_line
			(start -0.5305 1)
			(end -0.5305 -1.001)
			(stroke
				(width 0.15)
				(type solid)
			)
			(layer "F.Fab")
		)
		(fp_line
			(start 0.5305 -1.001)
			(end 0.5305 1)
			(stroke
				(width 0.15)
				(type solid)
			)
			(layer "F.Fab")
		)
		(fp_line
			(start 0.5305 1)
			(end -0.5305 1)
			(stroke
				(width 0.15)
				(type solid)
			)
			(layer "F.Fab")
		)
		(fp_text user "Author: Antmicro"
			(at -0.527 7.105 0)
			(layer "F.Fab")
			(effects
				(font
					(size 0.7 0.7)
					(thickness 0.15)
				)
				(justify left bottom)
			)
		)
		(fp_text user "License: Apache-2.0"
			(at -0.527 8.306 0)
			(layer "F.Fab")
			(effects
				(font
					(size 0.7 0.7)
					(thickness 0.15)
				)
				(justify left bottom)
			)
		)
		(fp_text user "${REFERENCE}"
			(at -0.527 5.905 0)
			(layer "F.Fab")
			(effects
				(font
					(size 0.7 0.7)
					(thickness 0.15)
				)
				(justify left bottom)
			)
		)
		(pad "1" smd roundrect
			(at -0.45 -0.75 180)
			(size 0.6 0.3)
			(layers "F.Cu" "F.Mask" "F.Paste")
			(roundrect_rratio 0.25)
			(net 619 "/FPGA GPIO/I^{2}C0.SDA")
			(pinfunction "B_{2}")
			(pintype "bidirectional")
		)
		(pad "2" smd roundrect
			(at -0.45 -0.25 180)
			(size 0.6 0.25)
			(layers "F.Cu" "F.Mask" "F.Paste")
			(roundrect_rratio 0.25)
			(net 417 "GND")
			(pinfunction "GND")
			(pintype "power_in")
		)
		(pad "3" smd roundrect
			(at -0.45 0.25 180)
			(size 0.6 0.25)
			(layers "F.Cu" "F.Mask" "F.Paste")
			(roundrect_rratio 0.25)
			(net 649 "VDD")
			(pinfunction "VCC_{A}")
			(pintype "power_in")
		)
		(pad "4" smd roundrect
			(at -0.45 0.75 180)
			(size 0.6 0.3)
			(layers "F.Cu" "F.Mask" "F.Paste")
			(roundrect_rratio 0.25)
			(net 509 "/FPGA GPIO/SDA0_PF")
			(pinfunction "A_{2}")
			(pintype "bidirectional")
		)
		(pad "5" smd roundrect
			(at 0.45 0.75 180)
			(size 0.6 0.3)
			(layers "F.Cu" "F.Mask" "F.Paste")
			(roundrect_rratio 0.25)
			(net 350 "/FPGA GPIO/SCL0_PF")
			(pinfunction "A_{1}")
			(pintype "bidirectional")
		)
		(pad "6" smd roundrect
			(at 0.45 0.25 180)
			(size 0.6 0.25)
			(layers "F.Cu" "F.Mask" "F.Paste")
			(roundrect_rratio 0.25)
			(net 649 "VDD")
			(pinfunction "OE")
			(pintype "input")
		)
		(pad "7" smd roundrect
			(at 0.45 -0.25 180)
			(size 0.6 0.25)
			(layers "F.Cu" "F.Mask" "F.Paste")
			(roundrect_rratio 0.25)
			(net 50 "+3V3")
			(pinfunction "VCC_{B}")
			(pintype "power_in")
		)
		(pad "8" smd roundrect
			(at 0.45 -0.75 180)
			(size 0.6 0.3)
			(layers "F.Cu" "F.Mask" "F.Paste")
			(roundrect_rratio 0.25)
			(net 623 "/FPGA GPIO/I^{2}C0.SCL")
			(pinfunction "B_{1}")
			(pintype "bidirectional")
		)
	)
)
